(kicad_pcb
	(version 20260206)
	(generator "pcbnew")
	(generator_version "10.0")
	(general
		(thickness 1.6)
		(legacy_teardrops no)
	)
	(paper "A4")
	(title_block
		(title "01162023_DA0F0TEBIF0_F0T_Expander_BD_F_brd_V02_OCP.brd")
		(comment 1 "Grand Teton / footprints 5092-5098 of 9728")
	)
	(layers
		(0 "F.Cu" signal "TOP")
		(4 "In1.Cu" signal "GND")
		(6 "In2.Cu" signal "VCC")
		(8 "In3.Cu" signal "VCC1")
		(10 "In4.Cu" signal "GND1")
		(12 "In5.Cu" signal "IN1")
		(14 "In6.Cu" signal "GND2")
		(16 "In7.Cu" signal "IN2")
		(18 "In8.Cu" signal "GND3")
		(20 "In9.Cu" signal "IN3")
		(22 "In10.Cu" signal "GND4")
		(24 "In11.Cu" signal "IN4")
		(26 "In12.Cu" signal "GND5")
		(28 "In13.Cu" signal "IN5")
		(30 "In14.Cu" signal "GND6")
		(32 "In15.Cu" signal "IN6")
		(34 "In16.Cu" signal "GND7")
		(2 "B.Cu" signal "BOTTOM")
		(9 "F.Adhes" user "F.Adhesive")
		(11 "B.Adhes" user "B.Adhesive")
		(13 "F.Paste" user "Package Geometry/Pastemask Top")
		(15 "B.Paste" user "Package Geometry/Pastemask Bottom")
		(5 "F.SilkS" user "Ref Des/Silkscreen Top")
		(7 "B.SilkS" user "Ref Des/Silkscreen Bottom")
		(1 "F.Mask" user "Board Geometry/Soldermask Top")
		(3 "B.Mask" user "Board Geometry/Soldermask Bottom")
		(17 "Dwgs.User" user "User.Drawings")
		(19 "Cmts.User" user "User.Comments")
		(21 "Eco1.User" user "User.Eco1")
		(23 "Eco2.User" user "User.Eco2")
		(25 "Edge.Cuts" user "Board Geometry/Outline")
		(27 "Margin" user)
		(31 "F.CrtYd" user "Package Geometry/Place Bound Top")
		(29 "B.CrtYd" user "Package Geometry/Place Bound Bottom")
		(35 "F.Fab" user "Ref Des/Assembly Top")
		(33 "B.Fab" user "Ref Des/Assembly Bottom")
	)
	(footprint ""
		(layer "F.Cu")
		(at 80.341724 -27.006296 -90)
		(property "Reference" "PR6926"
			(at 0 0 270)
			(layer "F.SilkS")
			(hide yes)
			(effects
				(font
					(size 1.27 1.27)
				)
			)
		)
		(property "Value" ""
			(at 0 0 270)
			(layer "F.Fab")
			(effects
				(font
					(size 1.27 1.27)
				)
			)
		)
		(duplicate_pad_numbers_are_jumpers no)
		(fp_line
			(start -0.7874 0.4064)
			(end -0.7874 -0.4064)
			(stroke
				(width 0.1524)
				(type default)
			)
			(layer "F.SilkS")
		)
		(fp_line
			(start 0.7874 0.4064)
			(end -0.7874 0.4064)
			(stroke
				(width 0.1524)
				(type default)
			)
			(layer "F.SilkS")
		)
		(fp_line
			(start -0.7874 -0.4064)
			(end 0.7874 -0.4064)
			(stroke
				(width 0.1524)
				(type default)
			)
			(layer "F.SilkS")
		)
		(fp_line
			(start 0.7874 -0.4064)
			(end 0.7874 0.4064)
			(stroke
				(width 0.1524)
				(type default)
			)
			(layer "F.SilkS")
		)
		(fp_line
			(start -0.67945 0.3048)
			(end -0.67945 -0.305054)
			(stroke
				(width 0.1)
				(type default)
			)
			(layer "F.Fab")
		)
		(fp_line
			(start -0.12065 0.3048)
			(end -0.67945 0.3048)
			(stroke
				(width 0.1)
				(type default)
			)
			(layer "F.Fab")
		)
		(fp_line
			(start 0.120396 0.3048)
			(end 0.120396 0.2794)
			(stroke
				(width 0.1)
				(type default)
			)
			(layer "F.Fab")
		)
		(fp_line
			(start 0.67945 0.3048)
			(end 0.120396 0.3048)
			(stroke
				(width 0.1)
				(type default)
			)
			(layer "F.Fab")
		)
		(fp_line
			(start -0.12065 0.2794)
			(end -0.12065 0.3048)
			(stroke
				(width 0.1)
				(type default)
			)
			(layer "F.Fab")
		)
		(fp_line
			(start 0.120396 0.2794)
			(end -0.12065 0.2794)
			(stroke
				(width 0.1)
				(type default)
			)
			(layer "F.Fab")
		)
		(fp_line
			(start -0.12065 -0.2794)
			(end 0.12065 -0.2794)
			(stroke
				(width 0.1)
				(type default)
			)
			(layer "F.Fab")
		)
		(fp_line
			(start 0.12065 -0.2794)
			(end 0.12065 -0.3048)
			(stroke
				(width 0.1)
				(type default)
			)
			(layer "F.Fab")
		)
		(fp_line
			(start 0.12065 -0.3048)
			(end 0.67945 -0.3048)
			(stroke
				(width 0.1)
				(type default)
			)
			(layer "F.Fab")
		)
		(fp_line
			(start 0.67945 -0.3048)
			(end 0.67945 0.3048)
			(stroke
				(width 0.1)
				(type default)
			)
			(layer "F.Fab")
		)
		(fp_line
			(start -0.67945 -0.305054)
			(end -0.12065 -0.305054)
			(stroke
				(width 0.1)
				(type default)
			)
			(layer "F.Fab")
		)
		(fp_line
			(start -0.12065 -0.305054)
			(end -0.12065 -0.2794)
			(stroke
				(width 0.1)
				(type default)
			)
			(layer "F.Fab")
		)
		(pad "1" smd circle
			(at -0.40005 0 270)
			(size 0 0)
			(layers "F.Cu" "F.Mask" "F.Paste")
			(net "P3V3_SSD3_CO_ILIMIT")
		)
		(pad "2" smd circle
			(at 0.40005 0 270)
			(size 0 0)
			(layers "F.Cu" "F.Mask" "F.Paste")
			(net "GND")
		)
	)
	(footprint ""
		(layer "F.Cu")
		(at 255.867916 -19.453098)
		(property "Reference" "R1695"
			(at 0 0 0)
			(layer "F.SilkS")
			(hide yes)
			(effects
				(font
					(size 1.27 1.27)
				)
			)
		)
		(property "Value" ""
			(at 0 0 0)
			(layer "F.Fab")
			(effects
				(font
					(size 1.27 1.27)
				)
			)
		)
		(duplicate_pad_numbers_are_jumpers no)
		(fp_line
			(start -0.7874 -0.4064)
			(end 0.7874 -0.4064)
			(stroke
				(width 0.1524)
				(type default)
			)
			(layer "F.SilkS")
		)
		(fp_line
			(start -0.7874 0.4064)
			(end -0.7874 -0.4064)
			(stroke
				(width 0.1524)
				(type default)
			)
			(layer "F.SilkS")
		)
		(fp_line
			(start 0.7874 -0.4064)
			(end 0.7874 0.4064)
			(stroke
				(width 0.1524)
				(type default)
			)
			(layer "F.SilkS")
		)
		(fp_line
			(start 0.7874 0.4064)
			(end -0.7874 0.4064)
			(stroke
				(width 0.1524)
				(type default)
			)
			(layer "F.SilkS")
		)
		(fp_line
			(start -0.67945 -0.305054)
			(end -0.12065 -0.305054)
			(stroke
				(width 0.1)
				(type default)
			)
			(layer "F.Fab")
		)
		(fp_line
			(start -0.67945 0.3048)
			(end -0.67945 -0.305054)
			(stroke
				(width 0.1)
				(type default)
			)
			(layer "F.Fab")
		)
		(fp_line
			(start -0.12065 -0.305054)
			(end -0.12065 -0.2794)
			(stroke
				(width 0.1)
				(type default)
			)
			(layer "F.Fab")
		)
		(fp_line
			(start -0.12065 -0.2794)
			(end 0.12065 -0.2794)
			(stroke
				(width 0.1)
				(type default)
			)
			(layer "F.Fab")
		)
		(fp_line
			(start -0.12065 0.2794)
			(end -0.12065 0.3048)
			(stroke
				(width 0.1)
				(type default)
			)
			(layer "F.Fab")
		)
		(fp_line
			(start -0.12065 0.3048)
			(end -0.67945 0.3048)
			(stroke
				(width 0.1)
				(type default)
			)
			(layer "F.Fab")
		)
		(fp_line
			(start 0.120396 0.2794)
			(end -0.12065 0.2794)
			(stroke
				(width 0.1)
				(type default)
			)
			(layer "F.Fab")
		)
		(fp_line
			(start 0.120396 0.3048)
			(end 0.120396 0.2794)
			(stroke
				(width 0.1)
				(type default)
			)
			(layer "F.Fab")
		)
		(fp_line
			(start 0.12065 -0.3048)
			(end 0.67945 -0.3048)
			(stroke
				(width 0.1)
				(type default)
			)
			(layer "F.Fab")
		)
		(fp_line
			(start 0.12065 -0.2794)
			(end 0.12065 -0.3048)
			(stroke
				(width 0.1)
				(type default)
			)
			(layer "F.Fab")
		)
		(fp_line
			(start 0.67945 -0.3048)
			(end 0.67945 0.3048)
			(stroke
				(width 0.1)
				(type default)
			)
			(layer "F.Fab")
		)
		(fp_line
			(start 0.67945 0.3048)
			(end 0.120396 0.3048)
			(stroke
				(width 0.1)
				(type default)
			)
			(layer "F.Fab")
		)
		(pad "1" smd circle
			(at -0.40005 0)
			(size 0 0)
			(layers "F.Cu" "F.Mask" "F.Paste")
			(net "SMB_ISO_SSD8_R_SDA")
		)
		(pad "2" smd circle
			(at 0.40005 0)
			(size 0 0)
			(layers "F.Cu" "F.Mask" "F.Paste")
			(net "SMB_ISO_SSD8_SDA")
		)
	)
	(footprint ""
		(layer "F.Cu")
		(at 454.930002 -251.37364 180)
		(property "Reference" "R6584"
			(at 0 0 180)
			(layer "F.SilkS")
			(hide yes)
			(effects
				(font
					(size 1.27 1.27)
				)
			)
		)
		(property "Value" ""
			(at 0 0 180)
			(layer "F.Fab")
			(effects
				(font
					(size 1.27 1.27)
				)
			)
		)
		(duplicate_pad_numbers_are_jumpers no)
		(fp_line
			(start 0.7874 0.4064)
			(end -0.7874 0.4064)
			(stroke
				(width 0.1524)
				(type default)
			)
			(layer "F.SilkS")
		)
		(fp_line
			(start 0.7874 -0.4064)
			(end 0.7874 0.4064)
			(stroke
				(width 0.1524)
				(type default)
			)
			(layer "F.SilkS")
		)
		(fp_line
			(start -0.7874 0.4064)
			(end -0.7874 -0.4064)
			(stroke
				(width 0.1524)
				(type default)
			)
			(layer "F.SilkS")
		)
		(fp_line
			(start -0.7874 -0.4064)
			(end 0.7874 -0.4064)
			(stroke
				(width 0.1524)
				(type default)
			)
			(layer "F.SilkS")
		)
		(fp_line
			(start 0.67945 0.3048)
			(end 0.120396 0.3048)
			(stroke
				(width 0.1)
				(type default)
			)
			(layer "F.Fab")
		)
		(fp_line
			(start 0.67945 -0.3048)
			(end 0.67945 0.3048)
			(stroke
				(width 0.1)
				(type default)
			)
			(layer "F.Fab")
		)
		(fp_line
			(start 0.12065 -0.2794)
			(end 0.12065 -0.3048)
			(stroke
				(width 0.1)
				(type default)
			)
			(layer "F.Fab")
		)
		(fp_line
			(start 0.12065 -0.3048)
			(end 0.67945 -0.3048)
			(stroke
				(width 0.1)
				(type default)
			)
			(layer "F.Fab")
		)
		(fp_line
			(start 0.120396 0.3048)
			(end 0.120396 0.2794)
			(stroke
				(width 0.1)
				(type default)
			)
			(layer "F.Fab")
		)
		(fp_line
			(start 0.120396 0.2794)
			(end -0.12065 0.2794)
			(stroke
				(width 0.1)
				(type default)
			)
			(layer "F.Fab")
		)
		(fp_line
			(start -0.12065 0.3048)
			(end -0.67945 0.3048)
			(stroke
				(width 0.1)
				(type default)
			)
			(layer "F.Fab")
		)
		(fp_line
			(start -0.12065 0.2794)
			(end -0.12065 0.3048)
			(stroke
				(width 0.1)
				(type default)
			)
			(layer "F.Fab")
		)
		(fp_line
			(start -0.12065 -0.2794)
			(end 0.12065 -0.2794)
			(stroke
				(width 0.1)
				(type default)
			)
			(layer "F.Fab")
		)
		(fp_line
			(start -0.12065 -0.305054)
			(end -0.12065 -0.2794)
			(stroke
				(width 0.1)
				(type default)
			)
			(layer "F.Fab")
		)
		(fp_line
			(start -0.67945 0.3048)
			(end -0.67945 -0.305054)
			(stroke
				(width 0.1)
				(type default)
			)
			(layer "F.Fab")
		)
		(fp_line
			(start -0.67945 -0.305054)
			(end -0.12065 -0.305054)
			(stroke
				(width 0.1)
				(type default)
			)
			(layer "F.Fab")
		)
		(pad "1" smd circle
			(at -0.40005 0 180)
			(size 0 0)
			(layers "F.Cu" "F.Mask" "F.Paste")
			(net "PWR_EN_PEX_R")
		)
		(pad "2" smd circle
			(at 0.40005 0 180)
			(size 0 0)
			(layers "F.Cu" "F.Mask" "F.Paste")
			(net "PEX3_P1V8_PLL_EN")
		)
	)
	(footprint ""
		(layer "F.Cu")
		(at 175.0949 -98.734372)
		(property "Reference" "R154"
			(at 0 0 0)
			(layer "F.SilkS")
			(hide yes)
			(effects
				(font
					(size 1.27 1.27)
				)
			)
		)
		(property "Value" ""
			(at 0 0 0)
			(layer "F.Fab")
			(effects
				(font
					(size 1.27 1.27)
				)
			)
		)
		(duplicate_pad_numbers_are_jumpers no)
		(fp_line
			(start -0.7874 -0.4064)
			(end 0.7874 -0.4064)
			(stroke
				(width 0.1524)
				(type default)
			)
			(layer "F.SilkS")
		)
		(fp_line
			(start -0.7874 0.4064)
			(end -0.7874 -0.4064)
			(stroke
				(width 0.1524)
				(type default)
			)
			(layer "F.SilkS")
		)
		(fp_line
			(start 0.7874 -0.4064)
			(end 0.7874 0.4064)
			(stroke
				(width 0.1524)
				(type default)
			)
			(layer "F.SilkS")
		)
		(fp_line
			(start 0.7874 0.4064)
			(end -0.7874 0.4064)
			(stroke
				(width 0.1524)
				(type default)
			)
			(layer "F.SilkS")
		)
		(fp_line
			(start -0.67945 -0.305054)
			(end -0.12065 -0.305054)
			(stroke
				(width 0.1)
				(type default)
			)
			(layer "F.Fab")
		)
		(fp_line
			(start -0.67945 0.3048)
			(end -0.67945 -0.305054)
			(stroke
				(width 0.1)
				(type default)
			)
			(layer "F.Fab")
		)
		(fp_line
			(start -0.12065 -0.305054)
			(end -0.12065 -0.2794)
			(stroke
				(width 0.1)
				(type default)
			)
			(layer "F.Fab")
		)
		(fp_line
			(start -0.12065 -0.2794)
			(end 0.12065 -0.2794)
			(stroke
				(width 0.1)
				(type default)
			)
			(layer "F.Fab")
		)
		(fp_line
			(start -0.12065 0.2794)
			(end -0.12065 0.3048)
			(stroke
				(width 0.1)
				(type default)
			)
			(layer "F.Fab")
		)
		(fp_line
			(start -0.12065 0.3048)
			(end -0.67945 0.3048)
			(stroke
				(width 0.1)
				(type default)
			)
			(layer "F.Fab")
		)
		(fp_line
			(start 0.120396 0.2794)
			(end -0.12065 0.2794)
			(stroke
				(width 0.1)
				(type default)
			)
			(layer "F.Fab")
		)
		(fp_line
			(start 0.120396 0.3048)
			(end 0.120396 0.2794)
			(stroke
				(width 0.1)
				(type default)
			)
			(layer "F.Fab")
		)
		(fp_line
			(start 0.12065 -0.3048)
			(end 0.67945 -0.3048)
			(stroke
				(width 0.1)
				(type default)
			)
			(layer "F.Fab")
		)
		(fp_line
			(start 0.12065 -0.2794)
			(end 0.12065 -0.3048)
			(stroke
				(width 0.1)
				(type default)
			)
			(layer "F.Fab")
		)
		(fp_line
			(start 0.67945 -0.3048)
			(end 0.67945 0.3048)
			(stroke
				(width 0.1)
				(type default)
			)
			(layer "F.Fab")
		)
		(fp_line
			(start 0.67945 0.3048)
			(end 0.120396 0.3048)
			(stroke
				(width 0.1)
				(type default)
			)
			(layer "F.Fab")
		)
		(pad "1" smd circle
			(at -0.40005 0)
			(size 0 0)
			(layers "F.Cu" "F.Mask" "F.Paste")
			(net "NIC3_RBT_ARB_OUT")
		)
		(pad "2" smd circle
			(at 0.40005 0)
			(size 0 0)
			(layers "F.Cu" "F.Mask" "F.Paste")
			(net "NIC3_RBT_ARB_IN")
		)
	)
	(footprint ""
		(layer "F.Cu")
		(at 154.707844 -162.044126 180)
		(property "Reference" "R124"
			(at 0 0 180)
			(layer "F.SilkS")
			(hide yes)
			(effects
				(font
					(size 1.27 1.27)
				)
			)
		)
		(property "Value" ""
			(at 0 0 180)
			(layer "F.Fab")
			(effects
				(font
					(size 1.27 1.27)
				)
			)
		)
		(duplicate_pad_numbers_are_jumpers no)
		(fp_line
			(start 0.7874 0.4064)
			(end -0.7874 0.4064)
			(stroke
				(width 0.1524)
				(type default)
			)
			(layer "F.SilkS")
		)
		(fp_line
			(start 0.7874 -0.4064)
			(end 0.7874 0.4064)
			(stroke
				(width 0.1524)
				(type default)
			)
			(layer "F.SilkS")
		)
		(fp_line
			(start -0.7874 0.4064)
			(end -0.7874 -0.4064)
			(stroke
				(width 0.1524)
				(type default)
			)
			(layer "F.SilkS")
		)
		(fp_line
			(start -0.7874 -0.4064)
			(end 0.7874 -0.4064)
			(stroke
				(width 0.1524)
				(type default)
			)
			(layer "F.SilkS")
		)
		(fp_line
			(start 0.67945 0.3048)
			(end 0.120396 0.3048)
			(stroke
				(width 0.1)
				(type default)
			)
			(layer "F.Fab")
		)
		(fp_line
			(start 0.67945 -0.3048)
			(end 0.67945 0.3048)
			(stroke
				(width 0.1)
				(type default)
			)
			(layer "F.Fab")
		)
		(fp_line
			(start 0.12065 -0.2794)
			(end 0.12065 -0.3048)
			(stroke
				(width 0.1)
				(type default)
			)
			(layer "F.Fab")
		)
		(fp_line
			(start 0.12065 -0.3048)
			(end 0.67945 -0.3048)
			(stroke
				(width 0.1)
				(type default)
			)
			(layer "F.Fab")
		)
		(fp_line
			(start 0.120396 0.3048)
			(end 0.120396 0.2794)
			(stroke
				(width 0.1)
				(type default)
			)
			(layer "F.Fab")
		)
		(fp_line
			(start 0.120396 0.2794)
			(end -0.12065 0.2794)
			(stroke
				(width 0.1)
				(type default)
			)
			(layer "F.Fab")
		)
		(fp_line
			(start -0.12065 0.3048)
			(end -0.67945 0.3048)
			(stroke
				(width 0.1)
				(type default)
			)
			(layer "F.Fab")
		)
		(fp_line
			(start -0.12065 0.2794)
			(end -0.12065 0.3048)
			(stroke
				(width 0.1)
				(type default)
			)
			(layer "F.Fab")
		)
		(fp_line
			(start -0.12065 -0.2794)
			(end 0.12065 -0.2794)
			(stroke
				(width 0.1)
				(type default)
			)
			(layer "F.Fab")
		)
		(fp_line
			(start -0.12065 -0.305054)
			(end -0.12065 -0.2794)
			(stroke
				(width 0.1)
				(type default)
			)
			(layer "F.Fab")
		)
		(fp_line
			(start -0.67945 0.3048)
			(end -0.67945 -0.305054)
			(stroke
				(width 0.1)
				(type default)
			)
			(layer "F.Fab")
		)
		(fp_line
			(start -0.67945 -0.305054)
			(end -0.12065 -0.305054)
			(stroke
				(width 0.1)
				(type default)
			)
			(layer "F.Fab")
		)
		(pad "1" smd circle
			(at -0.40005 0 180)
			(size 0 0)
			(layers "F.Cu" "F.Mask" "F.Paste")
			(net "PWRGD_NIC2_PWR_GOOD")
		)
		(pad "2" smd circle
			(at 0.40005 0 180)
			(size 0 0)
			(layers "F.Cu" "F.Mask" "F.Paste")
			(net "GND")
		)
	)
	(footprint ""
		(layer "F.Cu")
		(at 80.019398 -129.880106 180)
		(property "Reference" "C24"
			(at 0 0 180)
			(layer "F.SilkS")
			(hide yes)
			(effects
				(font
					(size 1.27 1.27)
				)
			)
		)
		(property "Value" ""
			(at 0 0 180)
			(layer "F.Fab")
			(effects
				(font
					(size 1.27 1.27)
				)
			)
		)
		(duplicate_pad_numbers_are_jumpers no)
		(fp_line
			(start 0.299974 0.150114)
			(end -0.299974 0.150114)
			(stroke
				(width 0.1)
				(type default)
			)
			(layer "F.Fab")
		)
		(fp_line
			(start 0.299974 -0.150114)
			(end 0.299974 0.150114)
			(stroke
				(width 0.1)
				(type default)
			)
			(layer "F.Fab")
		)
		(fp_line
			(start -0.299974 0.150114)
			(end -0.299974 -0.150114)
			(stroke
				(width 0.1)
				(type default)
			)
			(layer "F.Fab")
		)
		(fp_line
			(start -0.299974 -0.150114)
			(end 0.299974 -0.150114)
			(stroke
				(width 0.1)
				(type default)
			)
			(layer "F.Fab")
		)
		(pad "1" smd rect
			(at -0.2667 0 180)
			(size 0.3048 0.381)
			(layers "F.Cu" "F.Mask" "F.Paste")
			(net "P5E_PEX0_STN0_TX_DN<4>")
		)
		(pad "2" smd rect
			(at 0.2667 0 180)
			(size 0.3048 0.381)
			(layers "F.Cu" "F.Mask" "F.Paste")
			(net "P5E_PEX0_STN0_TX_C_DN<4>")
		)
	)
	(footprint ""
		(layer "F.Cu")
		(at 463.502756 -254.35433 -90)
		(property "Reference" "C4413"
			(at 0 0 270)
			(layer "F.SilkS")
			(hide yes)
			(effects
				(font
					(size 1.27 1.27)
				)
			)
		)
		(property "Value" ""
			(at 0 0 270)
			(layer "F.Fab")
			(effects
				(font
					(size 1.27 1.27)
				)
			)
		)
		(duplicate_pad_numbers_are_jumpers no)
		(fp_line
			(start -1.524 0.762)
			(end -1.524 -0.762)
			(stroke
				(width 0.1524)
				(type default)
			)
			(layer "F.SilkS")
		)
		(fp_line
			(start 1.524 0.762)
			(end -1.524 0.762)
			(stroke
				(width 0.1524)
				(type default)
			)
			(layer "F.SilkS")
		)
		(fp_line
			(start -1.524 -0.762)
			(end 1.524 -0.762)
			(stroke
				(width 0.1524)
				(type default)
			)
			(layer "F.SilkS")
		)
		(fp_line
			(start 1.524 -0.762)
			(end 1.524 0.762)
			(stroke
				(width 0.1524)
				(type default)
			)
			(layer "F.SilkS")
		)
		(fp_line
			(start -1.1049 0.724916)
			(end 1.1049 0.724916)
			(stroke
				(width 0.1)
				(type default)
			)
			(layer "F.Fab")
		)
		(fp_line
			(start 1.1049 0.724916)
			(end 1.1049 -0.724916)
			(stroke
				(width 0.1)
				(type default)
			)
			(layer "F.Fab")
		)
		(fp_line
			(start -1.1049 -0.724916)
			(end -1.1049 0.724916)
			(stroke
				(width 0.1)
				(type default)
			)
			(layer "F.Fab")
		)
		(fp_line
			(start 1.1049 -0.724916)
			(end -1.1049 -0.724916)
			(stroke
				(width 0.1)
				(type default)
			)
			(layer "F.Fab")
		)
		(pad "1" smd rect
			(at -0.889 0 90)
			(size 1.016 1.27)
			(layers "F.Cu" "F.Mask" "F.Paste")
			(net "P1V25_SERDES_VDDPLL_PEX3_C11")
		)
		(pad "2" smd rect
			(at 0.889 0 90)
			(size 1.016 1.27)
			(layers "F.Cu" "F.Mask" "F.Paste")
			(net "GND")
		)
		(zone
			(layer "F.Cu")
			(hatch none 0.5)
			(connect_pads
				(clearance 0)
			)
			(min_thickness 0.25)
			(keepout
				(tracks not_allowed)
				(vias allowed)
				(pads allowed)
				(copperpour not_allowed)
				(footprints allowed)
			)
			(placement
				(enabled no)
				(sheetname "")
			)
			(fill
				(thermal_gap 0.5)
				(thermal_bridge_width 0.5)
				(island_removal_mode 0)
			)
			(polygon
				(pts
					(xy 464.227672 -254.68453) (xy 462.77784 -254.68453) (xy 462.77784 -254.02413) (xy 464.227672 -254.02413)
				)
			)
		)
	)
)
